POWER AND GROUND LIST - 1  
DESIGNATOR       PART TYPE        
END POWER AND GROUND LIST
